%FSTAX25Y25*%
%MOIN*%
%SFA1B1*%

%IPPOS*%
%ADD18C,0.005000*%
%ADD41R,0.028000X0.165000*%
%ADD42R,0.028000X0.126000*%
%ADD108C,0.120000*%
%ADD112C,0.008000*%
%ADD113C,0.020000*%
%ADD114C,0.012000*%
%ADD119C,0.065980*%
%ADD120C,0.075000*%
%ADD121R,0.059060X0.059060*%
%ADD122C,0.059060*%
%ADD123C,0.021660*%
%ADD124C,0.112000*%
%ADD125C,0.250000*%
%ADD126C,0.016000*%
%ADD127C,0.200000*%
%ADD128C,0.050000*%
%ADD129C,0.032000*%
%ADD130C,0.025000*%
%ADD131R,0.025200X0.026770*%
%ADD132C,0.030000*%
%ADD133R,0.098430X0.068900*%
%ADD134R,0.073820X0.067910*%
%LNtimecard-dc-beta-v1-1*%
%LPD*%
G36*
X0681102Y0194882D02*
X061811D01*
Y0222441*
X0681102*
Y0194882*
G37*
%LNtimecard-dc-beta-v1-2*%
%LPC*%
G36*
X0661102Y0219206D02*
X0660466D01*
X0659878Y0218963*
X0659428Y0218513*
X0659184Y0217925*
Y0217288*
X0659428Y02167*
X0659878Y021625*
X0660466Y0216006*
X0661102*
X0661691Y021625*
X0662141Y02167*
X0662384Y0217288*
Y0217925*
X0662141Y0218513*
X0661691Y0218963*
X0661102Y0219206*
G37*
G36*
X0639902Y0212706D02*
X0639266D01*
X0638678Y0212463*
X0638228Y0212013*
X0637984Y0211425*
Y0210788*
X0638228Y02102*
X0638678Y020975*
X0639266Y0209506*
X0639902*
X0640491Y020975*
X0640941Y02102*
X0641184Y0210788*
Y0211425*
X0640941Y0212013*
X0640491Y0212463*
X0639902Y0212706*
G37*
%LNtimecard-dc-beta-v1-3*%
%LPD*%
G54D18*
X0246982Y0041092D02*
D01*
X0246959Y0041065*
X0246938Y0041037*
X024692Y0041007*
X0246904Y0040976*
X0246889Y0040944*
X0246877Y0040912*
X0246868Y0040878*
X024686Y0040844*
X0246855Y0040809*
X0246853Y0040775*
X0246853Y0040762*
X028189Y0036527D02*
D01*
X028189Y0036504*
X0281893Y0036482*
X0281897Y0036459*
X0281902Y0036437*
X0281909Y0036416*
X0281917Y0036395*
X0281927Y0036375*
X0281939Y0036355*
X0281951Y0036337*
X0281965Y0036319*
X028198Y0036302*
X0281984Y0036299*
X0285433Y0036423D02*
D01*
X0285433Y003641*
X0285434Y0036398*
X0285436Y0036386*
X0285439Y0036374*
X0285443Y0036363*
X0285448Y0036351*
X0285453Y003634*
X0285459Y003633*
X0285466Y003632*
X0285473Y003631*
X0285482Y0036301*
X0285484Y0036299*
X0298039Y0040885D02*
D01*
X0298034Y004085*
X0298031Y0040815*
X0298031Y0040797*
X0270354Y0011106D02*
D01*
X0270375Y0011128*
X0270394Y0011152*
X0270412Y0011178*
X0270428Y0011204*
X0270442Y0011232*
X0270454Y001126*
X0270464Y001129*
X0270472Y001132*
X0270478Y001135*
X0270482Y0011381*
X0270483Y0011412*
X0270484Y001142*
X0301984Y0032913D02*
D01*
X0301962Y0032889*
X0301942Y0032864*
X0301923Y0032838*
X0301907Y0032811*
X0301893Y0032783*
X030188Y0032753*
X030187Y0032723*
X0301861Y0032692*
X0301855Y0032661*
X0301851Y0032629*
X030185Y0032597*
X030185Y003259*
X0297984Y0032913D02*
D01*
X0297972Y00329*
X0297961Y0032887*
X0297952Y0032873*
X0297943Y0032859*
X0297935Y0032844*
X0297929Y0032828*
X0297923Y0032812*
X0297919Y0032796*
X0297916Y0032779*
X0297914Y0032763*
X0297913Y0032746*
X0297913Y0032742*
X0285484Y0015081D02*
D01*
X0285488Y0014952*
X0285501Y0014824*
X0285524Y0014698*
X0285555Y0014573*
X0285595Y0014451*
X0285643Y0014332*
X0285699Y0014216*
X0285763Y0014105*
X0285835Y0013998*
X0285914Y0013897*
X0286Y0013802*
X0286023Y001378*
X0282165Y0032476D02*
D01*
X0282163Y0032519*
X0282158Y0032562*
X0282151Y0032604*
X0282141Y0032646*
X0282127Y0032687*
X0282111Y0032727*
X0282092Y0032766*
X0282071Y0032803*
X0282046Y0032839*
X028202Y0032873*
X0281991Y0032905*
X0281984Y0032913*
Y0014026D02*
D01*
X0281984Y0014001*
X0281987Y0013977*
X0281991Y0013953*
X0281997Y0013929*
X0282005Y0013906*
X0282014Y0013884*
X0282024Y0013862*
X0282037Y0013841*
X028205Y001382*
X0282065Y0013801*
X0282081Y0013783*
X0282086Y001378*
X0234984Y0032913D02*
D01*
X0234973Y0032902*
X0234964Y003289*
X0234955Y0032878*
X0234947Y0032865*
X0234941Y0032851*
X0234935Y0032838*
X023493Y0032823*
X0234926Y0032809*
X0234923Y0032794*
X0234921Y0032779*
X0234921Y0032764*
Y0032761*
X0282198Y0040785D02*
D01*
X0282166Y004077*
X0282135Y0040753*
X0282106Y0040735*
X0282078Y0040714*
X0282051Y0040691*
X0282026Y0040667*
X0282003Y0040641*
X0281982Y0040613*
X0281962Y0040584*
X0281945Y0040554*
X028193Y0040522*
X0281917Y004049*
X0281907Y0040456*
X0281899Y0040423*
X0281893Y0040388*
X028189Y0040353*
Y0040327*
X0266484Y0036299D02*
D01*
X0266492Y0036307*
X02665Y0036317*
X0266507Y0036327*
X0266513Y0036337*
X0266518Y0036348*
X0266523Y003636*
X0266527Y0036371*
X026653Y0036383*
X0266533Y0036395*
X0266534Y0036407*
X0266535Y0036419*
X0266535Y0036423*
X0234984Y0036299D02*
D01*
X0234992Y0036308*
X0235001Y0036318*
X0235008Y0036329*
X0235015Y003634*
X0235021Y0036352*
X0235026Y0036364*
X023503Y0036377*
X0235034Y0036389*
X0235036Y0036402*
X0235038Y0036415*
X0235039Y0036428*
Y0036432*
X0297984Y0036299D02*
D01*
X0297991Y0036307*
X0297998Y0036315*
X0298005Y0036325*
X0298011Y0036334*
X0298016Y0036344*
X029802Y0036355*
X0298024Y0036365*
X0298027Y0036376*
X0298029Y0036387*
X029803Y0036398*
X0298031Y003641*
X0298031Y0036413*
X0234842Y001378D02*
D01*
X0234865Y0013804*
X0234886Y001383*
X0234905Y0013858*
X0234923Y0013887*
X0234938Y0013917*
X0234951Y0013948*
X0234962Y001398*
X0234971Y0014013*
X0234977Y0014046*
X0234981Y0014079*
X0234983Y0014113*
X0234984Y0014122*
X0238779Y001378D02*
D01*
X0238812Y0013815*
X0238842Y0013853*
X023887Y0013893*
X0238896Y0013935*
X0238918Y0013978*
X0238937Y0014023*
X0238953Y0014069*
X0238965Y0014116*
X0238975Y0014164*
X023898Y0014213*
X0238983Y0014261*
X0238984Y0014274*
X0246654Y001378D02*
D01*
X0246691Y001382*
X0246726Y0013862*
X0246757Y0013907*
X0246785Y0013955*
X024681Y0014004*
X0246832Y0014054*
X024685Y0014106*
X0246864Y0014159*
X0246875Y0014213*
X0246881Y0014268*
X0246884Y0014323*
X0246884Y0014337*
X025059Y001378D02*
D01*
X0250686Y0013883*
X0250775Y0013993*
X0250856Y0014109*
X0250929Y001423*
X0250993Y0014356*
X0251048Y0014486*
X0251095Y001462*
X0251131Y0014757*
X0251158Y0014895*
X0251175Y0015036*
X0251183Y0015177*
X0251184Y0015213*
X0266338Y001378D02*
D01*
X0266361Y0013805*
X0266383Y0013832*
X0266403Y001386*
X0266421Y001389*
X0266437Y0013921*
X026645Y0013953*
X0266462Y0013986*
X0266471Y001402*
X0266477Y0014054*
X0266481Y0014088*
X0266483Y0014123*
X0266484Y0014131*
X0270275Y001378D02*
D01*
X0270308Y0013816*
X027034Y0013855*
X0270368Y0013895*
X0270394Y0013938*
X0270416Y0013982*
X0270436Y0014028*
X0270452Y0014075*
X0270465Y0014123*
X0270474Y0014172*
X0270481Y0014221*
X0270483Y0014271*
X0270484Y0014284*
X0301771Y001378D02*
D01*
X0301805Y0013817*
X0301837Y0013856*
X0301866Y0013898*
X0301892Y0013941*
X0301915Y0013986*
X0301935Y0014033*
X0301952Y0014081*
X0301965Y001413*
X0301974Y001418*
X0301981Y001423*
X0301983Y0014281*
X0301984Y0014293*
X0297834Y001378D02*
D01*
X0297858Y0013806*
X029788Y0013833*
X0297901Y0013863*
X0297919Y0013893*
X0297935Y0013925*
X0297949Y0013958*
X0297961Y0013992*
X029797Y0014026*
X0297977Y0014061*
X0297981Y0014097*
X0297983Y0014133*
X0297984Y0014141*
X0297913Y0011106D02*
D01*
X0297924Y0011118*
X0297935Y0011131*
X0297944Y0011145*
X0297953Y0011159*
X0297961Y0011174*
X0297967Y001119*
X0297973Y0011206*
X0297977Y0011222*
X029798Y0011239*
X0297982Y0011255*
X0297983Y0011272*
X0297984Y0011278*
X0246732Y0011106D02*
D01*
X0246732Y0011106*
X0246732Y0011106*
X0246732Y0011106*
X0246732Y0011106*
X0246732Y0011107*
X0246733*
D01*
X0246757Y0011133*
X024678Y0011161*
X0246801Y0011191*
X0246819Y0011222*
X0246836Y0011254*
X024685Y0011288*
X0246862Y0011322*
X0246871Y0011357*
X0246878Y0011392*
X0246883Y0011428*
X0246884Y0011464*
X0246884Y0011473*
X0266417Y0011106D02*
D01*
X0266427Y0011117*
X0266437Y001113*
X0266447Y0011143*
X0266455Y0011156*
X0266462Y0011171*
X0266468Y0011185*
X0266474Y0011201*
X0266478Y0011216*
X0266481Y0011232*
X0266483Y0011248*
X0266484Y0011264*
Y0011268*
X0285484Y0012598D02*
D01*
X0285489Y001245*
X0285504Y0012304*
X028553Y0012159*
X0285565Y0012016*
X0285611Y0011876*
X0285666Y0011739*
X028573Y0011607*
X0285804Y0011479*
X0285886Y0011357*
X0285977Y0011241*
X0286076Y0011132*
X02861Y0011108*
D01*
X02861Y0011107*
X02861Y0011107*
X0286101Y0011106*
X0286101Y0011106*
X0286102Y0011106*
X0246982Y0041092D02*
X0246987Y0041098D01*
X024685Y0040501D02*
X0246853Y0040762D01*
X028189Y0036527D02*
Y0040327D01*
X0285433Y0036423D02*
Y0040551D01*
X0298039Y0040885D02*
X0298044Y0040914D01*
X0298031Y0036413D02*
Y0040797D01*
X0301984Y0014293D02*
Y0032913D01*
X0297984Y0014141D02*
Y0032913D01*
X0285484Y0015081D02*
Y0032913D01*
X0281984Y0014026D02*
Y0032913D01*
X0234984Y0014122D02*
Y0032913D01*
X024685Y0036333D02*
Y0040501D01*
Y0036333D02*
X0246884Y0036299D01*
X0251181Y0036302D02*
Y0040551D01*
Y0036302D02*
X0251184Y0036299D01*
X0298044Y0040914D02*
X0298046Y0040915D01*
X0246987Y0041098D02*
X0246988Y0041099D01*
X0266535Y0036423D02*
Y0040551D01*
X0270472Y0036311D02*
X0270484Y0036299D01*
X0270472Y0036311D02*
Y0040551D01*
X0235039Y0036432D02*
Y0040551D01*
X0238976Y0036307D02*
X0238984Y0036299D01*
X0238976Y0036307D02*
Y0040551D01*
X0301969Y0036315D02*
X0301984Y0036299D01*
X0301969Y0036315D02*
Y0040551D01*
X0238984Y0014274D02*
Y0032913D01*
X0246884Y0014337D02*
Y0032913D01*
X0251184Y0015213D02*
Y0032913D01*
X0266484Y0014131D02*
Y0032913D01*
X0270484Y0014284D02*
Y0032913D01*
G54D41*
X0309646Y001378D03*
X0187599D03*
X0183661D03*
X0215158D03*
X0211221D03*
X0270275D03*
X0301771D03*
X0297834D03*
X0286023D03*
X0266338D03*
X0282086D03*
X025059D03*
X0246654D03*
X0238779D03*
X0234842D03*
X0219094D03*
X0195473D03*
X0199409D03*
X0203346D03*
X0207283D03*
X0258465D03*
X0242717D03*
X0230906D03*
X027815D03*
X0293898D03*
X0274213D03*
X0305709D03*
X0289961D03*
X0262402D03*
X0254527D03*
X0191535D03*
G54D42*
X0179725Y001573D03*
G54D108*
X0009984Y0258106D03*
Y0238106D03*
X0029984D03*
Y0258106D03*
X0009984Y0100606D03*
Y0080606D03*
X0029984D03*
Y0100606D03*
X0009984Y0153106D03*
Y0133106D03*
X0029984D03*
Y0153106D03*
X0009984Y0205606D03*
Y0185606D03*
X0029984D03*
Y0205606D03*
G54D112*
X0505905Y0416339D02*
X0533779D01*
X0543622Y0426181*
X0205709Y0050197D02*
Y0093504D01*
X0219094Y001378D02*
X0219488Y0014173D01*
X0205709Y0050197D02*
X0219094Y0036811D01*
X0188944Y0110268D02*
X0205709Y0093504D01*
X0219094Y001378D02*
Y0036811D01*
X0187279Y0037795D02*
X0207087D01*
X0179803Y0013056D02*
X0180296Y0013549D01*
X0188944Y0110268D02*
Y0151607D01*
X0180296Y0030812D02*
X0187279Y0037795D01*
X0180296Y0013549D02*
Y0030812D01*
X0320866Y0293307D02*
X0324135Y0296576D01*
X029813Y0229232D02*
X030315Y0234252D01*
Y0300197*
X0249016Y0354331D02*
X030315Y0300197D01*
X0362106Y0278543D02*
X0362156Y0278592D01*
X0350394Y0278543D02*
X0362106D01*
X0326803Y0295276D02*
X0333661D01*
X0350394Y0278543*
X0335314Y0296576D02*
X0350394Y0281496D01*
X0324135Y0296576D02*
X0335314D01*
X0350394Y0281496D02*
X0362205D01*
X0324803Y0293276D02*
X0326803Y0295276D01*
X025689Y0260827D02*
X0258858Y0262795D01*
X025689Y0231693D02*
Y0260827D01*
Y0231693D02*
X0259547Y0229035D01*
X0293069Y0257983D02*
X0293188Y0257863D01*
Y0217639D02*
Y0257863D01*
Y0217639D02*
X0293307Y021752D01*
X0298031Y0260531D02*
Y030333D01*
X0290059Y0217656D02*
Y026063D01*
X0226378Y0220472D02*
X0283384Y0163466D01*
X0386372*
X0226378Y0258583D02*
X0227835Y0260039D01*
X0226378Y0220472D02*
Y0258583D01*
X0227835Y0260039D02*
X0228051D01*
X0183809Y0233514D02*
X0278051Y0139272D01*
X0185335Y0233827D02*
X027674Y0142421D01*
X0182283Y0232874D02*
X0278843Y0136314D01*
X0341283*
X0278051Y0139272D02*
X0341142D01*
X018061Y0232709D02*
X0279402Y0133917D01*
X0341397*
X027674Y0142421D02*
X0341142D01*
X0289923Y021752D02*
X0290059Y0217656D01*
X0372475Y0166952D02*
X0372815Y0167291D01*
X0331802Y0166952D02*
X0372475D01*
X0372815Y0167291D02*
X0373031D01*
X0377513Y0169291D02*
X0386371Y017815D01*
X0309055Y0169291D02*
X0377513D01*
X0255906Y0222441D02*
Y0229134D01*
Y0222441D02*
X0309055Y0169291D01*
X0254905Y0346457D02*
X0298031Y030333D01*
X0238189Y0354331D02*
X0249016D01*
X0238189Y0346457D02*
X0254905D01*
X0238189Y0362205D02*
Y036811D01*
X0244094Y0374016*
X0329594*
X0383858Y0187992D02*
Y0319752D01*
X0329594Y0374016D02*
X0383858Y0319752D01*
X0373031Y0180118D02*
X0382558Y0189645D01*
X0347441Y0354331D02*
X0382558Y0319213D01*
Y0189645D02*
Y0319213D01*
X0373031Y0177165D02*
X0383858Y0187992D01*
X0271654Y0354331D02*
X0347441D01*
X0271654Y0346457D02*
X0353477D01*
X0380906Y0319028*
Y019685D02*
Y0319028D01*
X0373031Y0188976D02*
X0380906Y019685D01*
X0174606Y023002D02*
X0184144Y0220482D01*
X0164961Y023002D02*
X0174606D01*
X0184144Y0210148D02*
Y0220482D01*
X0174311Y0233661D02*
X0187402Y0220571D01*
X0166437Y0233661D02*
X0174311D01*
X0187402Y0210577D02*
Y0220571D01*
X0184429Y0207604D02*
X0187402Y0210577D01*
X0124397Y0322816D02*
Y0401594D01*
Y0322816D02*
X0185109Y0262103D01*
Y024806D02*
X0185335Y0247835D01*
X0185109Y024806D02*
Y0262103D01*
X0183809Y0233514D02*
Y0261565D01*
X010423Y0341144D02*
X0183809Y0261565D01*
X0084064Y0358653D02*
X0182283Y0260433D01*
X018061Y0232709D02*
Y0260268D01*
X0182283Y0232874D02*
Y0260433D01*
X0063897Y0376981D02*
X018061Y0260268D01*
X0063897Y0376981D02*
Y0401294D01*
X0084064Y0358653D02*
Y0401327D01*
X0185335Y0233827D02*
Y0247835D01*
X010423Y0341144D02*
Y040146D01*
X0188944Y0151606D02*
Y0151607D01*
X0149638Y0151606D02*
X0188944D01*
X0149606Y0151575D02*
X0149638Y0151606D01*
X0270354Y0011106D02*
X0270484Y0011236D01*
X0234921Y0011106D02*
X0234984Y0011169D01*
X030185Y0011106D02*
X0301984Y001124D01*
G54D113*
X0289104Y002438D02*
D01*
X0289001Y0024475*
X0288893Y0024562*
X0288778Y0024642*
X0288658Y0024714*
X0288534Y0024777*
X0288405Y0024832*
X0288273Y0024877*
X0288138Y0024913*
X0288001Y002494*
X0287863Y0024956*
X0287831Y002496*
X0243658Y0023533D02*
D01*
X0243546Y0023449*
X024344Y0023358*
X024334Y002326*
X0243248Y0023155*
X0243163Y0023044*
X0243087Y0022928*
X0243018Y0022806*
X0242959Y002268*
X0242908Y002255*
X0242866Y0022417*
X0242834Y0022281*
X0242811Y0022143*
X0242798Y0022004*
X0242795Y0021888*
X0191614Y0011106D02*
Y0024476D01*
X0305832Y0011151D02*
Y0013903D01*
X0287828Y002496D02*
X0287831D01*
X0289104Y002438D02*
X0289106Y0024379D01*
X0254606Y0011106D02*
Y0024484D01*
X026248Y0011106D02*
Y0023583D01*
X0242795Y0021888D02*
D01*
Y0011106D02*
Y0021888D01*
X0230984Y0011106D02*
Y0024606D01*
X0215114Y0011229D02*
Y002524D01*
X0211484Y002887D02*
X0215114Y002524D01*
X0187677Y0011106D02*
Y0024305D01*
X0184984Y0026998D02*
X0187677Y0024305D01*
X018374Y0025754D02*
X0184984Y0026998D01*
X018374Y0025591D02*
Y0025754D01*
Y0011106D02*
Y0025591D01*
X0289106Y0024379D02*
X0289886Y0023598D01*
X0243658Y0023533D02*
X0244706Y0024259D01*
X026248Y0023583D02*
X0263687Y0024791D01*
X0279921Y0025197D02*
X0279999D01*
X030593Y0023139D02*
X0307988Y0025197D01*
X0309744*
X0293497Y0014179D02*
Y0022426D01*
X0278273Y0023549D02*
X0279921Y0025197D01*
X0274213Y0024025D02*
X0275384Y0025197D01*
X0292326Y0023598D02*
X0293497Y0022426D01*
X0305832Y0013903D02*
X030593Y0014002D01*
X0293497Y0014179D02*
X0293898Y001378D01*
X0274213D02*
Y0024025D01*
X0275384Y0025197D02*
X0279921D01*
X0289886Y0013854D02*
X0289961Y001378D01*
X0289886Y0013854D02*
Y0023598D01*
X0292326*
X030593Y0014002D02*
Y0023139D01*
X0305787Y0011106D02*
X0305832Y0011151D01*
X0278273Y0013903D02*
Y0023549D01*
X027815Y001378D02*
X0278273Y0013903D01*
X0305709Y001378D02*
X0305832Y0013903D01*
X0211221Y0025591D02*
D01*
Y001378D02*
Y0025591D01*
X0215114Y0011229D02*
X0215236Y0011106D01*
G54D114*
X0275984Y0226772D02*
Y0319183D01*
Y0226772D02*
X0294094Y0208661D01*
X0275984Y0319183D02*
X0276772Y031997D01*
Y0320079*
X0294094Y0208661D02*
X0338583D01*
G54D119*
X019661Y040861D03*
X016661D03*
G54D120*
X0430778Y0258465D03*
X0418966D03*
X0407156D03*
X0398888Y0087992D03*
Y0247835D03*
X055873D03*
Y0167913D03*
Y0087992D03*
G54D121*
X0513622Y0426181D03*
G54D122*
X0523622Y0426181D03*
X0533622D03*
X0543622D03*
G54D123*
X0299014Y024384D03*
X0357136Y0209705D03*
Y0130965D03*
X0220274Y024384D03*
X0169644Y013097D03*
Y020971D03*
X0220275Y0095846D03*
X0299015D03*
G54D124*
X0019984Y0248106D03*
Y0090606D03*
Y0143106D03*
Y0195606D03*
G54D125*
X0028543Y0415206D03*
Y0036811D03*
G54D126*
X0045276Y0112205D03*
Y0121063D03*
X004626Y0227362D03*
Y0218504D03*
X0052689Y0207306D03*
X0107283Y0169291D03*
X0112205Y0117126D03*
X0101378Y0161417D03*
X0505905Y0416339D03*
X0338583Y0208661D03*
X0276772Y0320079D03*
X0270669Y0309087D03*
X0261811Y0309055D03*
X0249938Y0283527D03*
X0350394Y0303118D03*
X0356299D03*
X0366142D03*
X024311Y0267748D03*
X0244882Y0260236D03*
X0252953Y0229134D03*
X0248107D03*
X0237205Y0267717D03*
X0525591Y0298228D03*
X025889Y0242126D03*
X0525591Y0271654D03*
X0512795Y0279528D03*
Y028248D03*
X0519685Y0298228D03*
X0490158Y0270638D03*
X0505905Y0283465D03*
X05Y0295276D03*
X0279528Y0284449D03*
X0202756Y0409449D03*
X0302165Y0332677D03*
X0286417Y0327756D03*
X0288059Y0241869D03*
X0240158Y0242126D03*
X0160433Y0409449D03*
X0217488Y0357695D03*
X0201772Y0076772D03*
X0216535Y0068898D03*
X0595472Y0145669D03*
Y0141732D03*
X0597441Y0145669D03*
Y0141732D03*
X0595472Y0143701D03*
X0597441D03*
X0311024Y0281496D03*
Y0283465D03*
Y0285433D03*
X0331693Y0269685D03*
X0343504D03*
X0357185Y0272736D03*
X0312894Y0273721D03*
X0343504Y027559D03*
X0371477Y0289616D03*
X0304134Y0339567D03*
X0290158Y011063D03*
X0285039D03*
X027874D03*
X0272835D03*
X0207677Y002874D03*
Y0025591D03*
X0207087Y0037795D03*
X0209646Y0054134D03*
Y0056102D03*
X0211614Y0054134D03*
Y0056102D03*
X0213583Y0054134D03*
Y0056102D03*
X065748Y0208661D03*
X0620079Y019685D03*
Y0198819D03*
Y0200787D03*
X0622047Y019685D03*
Y0198819D03*
Y0200787D03*
Y0206693D03*
X0191614Y0024476D03*
X0627559Y0295276D03*
X0612992Y0276772D03*
X0667108Y0314014D03*
Y0315982D03*
X0663171Y0314014D03*
Y0315982D03*
X066514D03*
Y0314014D03*
X0272638Y0229331D03*
X0238189Y0354331D03*
X0271654Y0346457D03*
Y0354331D03*
Y0362205D03*
X0238189Y0346457D03*
Y0362205D03*
X0134843Y0151575D03*
X0107283Y0177165D03*
Y0231299D03*
X0101181Y0110433D03*
X011811Y0184055D03*
Y0237205D03*
X0120079Y0200787D03*
Y0253937D03*
X0163957Y035748D03*
X0181727D03*
X0199803Y0357283D03*
X021752Y0363189D03*
X0199803D03*
X0181794Y0362897D03*
X0163992Y0362811D03*
X0181102Y0409449D03*
X0173228D03*
X0064961Y0430118D03*
X0084646D03*
X0104331D03*
X0125D03*
X0288059Y0246457D03*
X0320866Y0293307D03*
X030115Y0291307D03*
X0329918Y0292362D03*
X0324803Y0293276D03*
X0362205Y0281496D03*
X0362156Y0278592D03*
X0294341Y0291289D03*
X025889Y0246457D03*
X0258858Y0262795D03*
X0293069Y0257983D03*
X0298031Y0260531D03*
X0290059Y026063D03*
X0247638Y0260236D03*
X0229035Y0246555D03*
X0293307Y021752D03*
X0289923D03*
X0331802Y0166952D03*
X0386372Y0163466D03*
X0354331Y0171291D03*
X0373031Y0167291D03*
X0360236Y0171291D03*
X0280512Y0229331D03*
X0523228Y0281496D03*
Y0273622D03*
X0286024Y0229232D03*
X029813D03*
X0268437Y0241831D03*
X0268701Y0246457D03*
X0245674Y0228738D03*
X0373031Y0208661D03*
Y0206693D03*
Y0204724D03*
Y0202756D03*
Y0188976D03*
Y0180118D03*
Y0177165D03*
X0354331Y0141732D03*
X0360236D03*
Y0151575D03*
X0354331D03*
Y0161417D03*
X0360236D03*
X0354331Y0181102D03*
X0360236D03*
X0354331Y0190945D03*
X0360236D03*
Y0200787D03*
X0354331D03*
X0338583Y0204724D03*
Y0202756D03*
Y0206693D03*
X0228051Y0260039D03*
X0184144Y0210148D03*
X0164961Y023002D03*
X0166437Y0233661D03*
X0184429Y0207604D03*
X0124397Y0401594D03*
X010423Y040146D03*
X0084064Y0401327D03*
X0063897Y0401294D03*
X0341142Y0142421D03*
Y0139272D03*
X0341283Y0136314D03*
X0341397Y0133917D03*
X0188944Y0151607D03*
X0240613Y0229269D03*
X0167484Y0198906D03*
X011998Y0250197D03*
X0119685Y0196752D03*
X011939Y0143504D03*
X0119587Y0091437D03*
X0278248Y0241831D03*
X0266437Y0229134D03*
X0262598D03*
X0259547Y0229035D03*
X0255906Y0229134D03*
X0248819Y0241831D03*
X0243307Y0229134D03*
X0233563Y0229035D03*
X0231004D03*
X023002Y024187D03*
X0278543Y0246457D03*
X0239173D03*
X024941D03*
X0492913Y0274803D03*
X0564921Y0290394D03*
X0570866Y0285433D03*
X0401575Y015748D03*
X0449803Y028937D03*
Y0284449D03*
X0397899Y0165616D03*
X0401575Y0168307D03*
X0401533Y0172321D03*
X0386371Y017815D03*
X0386433Y0160893D03*
X0386458Y0157787D03*
X0401461Y0175652D03*
X0401575Y017815D03*
Y0165354D03*
Y0162833D03*
Y0160433D03*
X0564961Y0280512D03*
X0564921Y0275551D03*
X0171884Y0149606D03*
X0167184D03*
X0149606Y0151575D03*
X0697884Y0183071D03*
X0231496Y0093307D03*
X0241339D03*
X0251575D03*
X0290551Y0093701D03*
X0266535Y011063D03*
X0261024D03*
X0251181Y0110591D03*
X0240945Y011063D03*
X0231102D03*
X0172184Y0168571D03*
X0167084D03*
X0636221Y0295276D03*
X0645084Y0246263D03*
Y0253543D03*
X0645276Y026063D03*
X0645182Y0267323D03*
X0645084Y0274016D03*
X065878Y0152931D03*
X0659449Y0167323D03*
Y0161024D03*
Y0177559D03*
Y0172047D03*
X0349705Y0064173D03*
X0270866Y0097638D03*
X0171484Y0159506D03*
X0260668Y009319D03*
X0276772Y0097638D03*
X0279921D03*
X0275984Y0079528D03*
X0274016Y0097638D03*
X0282677Y0079528D03*
X0262598D03*
X028937D03*
X0273228D03*
X0171884Y0179206D03*
X0167584Y0189106D03*
X0282677Y0097638D03*
X0269291Y0079528D03*
X0259842D03*
X026811Y0097638D03*
X0264961D03*
X0262205D03*
X0167184Y0179206D03*
X0266535Y0079528D03*
X0167184Y0139906D03*
X0279921Y0079528D03*
X0167084Y0159506D03*
X0286221Y0079528D03*
X0171684Y0139906D03*
X0172184Y0198906D03*
Y0189006D03*
X0251181Y0040551D03*
X0261024Y0027953D03*
X0257874D03*
X0298046Y0040915D03*
X0282198Y0040785D03*
X0274882Y0028231D03*
X0246988Y0041099D03*
X0290549Y0027951D03*
X0287828Y002496D03*
X0285433Y0040551D03*
X0277953Y0027953D03*
X0266535Y0040551D03*
X0270472D03*
X0235039D03*
X0238976D03*
X0293701Y0027953D03*
X0295747Y0025197D03*
X0301969Y0040551D03*
X0244706Y0024259D03*
X0241339Y0027953D03*
X0244488D03*
X0263687Y0024791D03*
X0279999Y0025197D03*
X0254606Y0024484D03*
X0309744Y0025197D03*
X0203484Y0024606D03*
X0230984D03*
X0662884Y0137206D03*
X0211221Y002874D03*
X0215158D03*
X0211221Y0025591D03*
X0215158D03*
X0183268D03*
X0185236D03*
X0187205D03*
X0183268Y002874D03*
X0185236D03*
X0187205D03*
X0349853Y0068206D03*
X0669478Y018309D03*
X0669984Y0188106D03*
X0694984Y0209506D03*
X0660784Y0217606D03*
X0639584Y0211106D03*
X0604884Y0217106D03*
X0600394Y0243021D03*
X0627484Y0239106D03*
X0052689Y0079006D03*
X0052789Y0102806D03*
X0052689Y0131406D03*
X0052589Y0155106D03*
X0052689Y0183906D03*
Y0236506D03*
X0052601Y0259389D03*
G54D127*
X0244124Y0317303D03*
X0482313Y0419665D03*
Y0317303D03*
X0244124Y0419665D03*
G54D128*
X0370669Y0072933D03*
G54D129*
X0619685Y0248425D03*
X0683858Y0164961D03*
G54D130*
X0370669Y0072933D02*
X0383829D01*
X0398888Y0087992*
G54D131*
X0301984Y0032913D03*
Y0036299D03*
X0234984D03*
Y0032913D03*
X0238984D03*
Y0036299D03*
X0246884D03*
Y0032913D03*
X0251184D03*
Y0036299D03*
X0266484Y0032913D03*
Y0036299D03*
X0270484Y0032913D03*
Y0036299D03*
X0281984Y0032913D03*
Y0036299D03*
X0285484D03*
Y0032913D03*
X0297984D03*
Y0036299D03*
G54D132*
X0209646Y0056102D02*
Y0113189D01*
X0482283Y0198819D02*
X0620079D01*
X0209646Y0113189D02*
X021752Y0121063D01*
X0302165*
X0311024Y0112205*
X0395669*
X0482283Y0198819*
G54D133*
X0212598Y005561D03*
G54D134*
X0213061Y0026852D03*
X0185187Y0026919D03*
M02*